# T6G (Grand Teton) — schematic netlist excerpt (pin names and nets, part order shuffled) for the footprints in the layout excerpt that follows; sources: Cadence DE-HDL packaged netlist, KiCad conversion of 04192023_DAF0TMB3IC0_F0TG_MB_C_brd_V02_OCP.brd

R2672  Q_RES  33.2 1% CHIP  pkg 0402LF  page 248 : A = SMB_BMC_SWB_BUF_R_SDA ; B = SMB_BMC_SWB_BUF_SDA
R3284  Q_RES  1K 1% CHIP  pkg 0402LF  page 111 : A = FM_P2E_EQB0 ; B = GND

(kicad_pcb
	(version 20260206)
	(generator "pcbnew")
	(generator_version "10.0")
	(general
		(thickness 1.6)
		(legacy_teardrops no)
	)
	(paper "A4")
	(title_block
		(title "04192023_DAF0TMB3IC0_F0TG_MB_C_brd_V02_OCP.brd")
		(comment 1 "Grand Teton / footprints 4480-4481 of 8354")
	)
	(layers
		(0 "F.Cu" signal "TOP")
		(4 "In1.Cu" signal "GND")
		(6 "In2.Cu" signal "IN1")
		(8 "In3.Cu" signal "GND1")
		(10 "In4.Cu" signal "IN2")
		(12 "In5.Cu" signal "GND2")
		(14 "In6.Cu" signal "IN3")
		(16 "In7.Cu" signal "GND3")
		(18 "In8.Cu" signal "VCC")
		(20 "In9.Cu" signal "VCC1")
		(22 "In10.Cu" signal "GND4")
		(24 "In11.Cu" signal "IN4")
		(26 "In12.Cu" signal "GND5")
		(28 "In13.Cu" signal "IN5")
		(30 "In14.Cu" signal "GND6")
		(32 "In15.Cu" signal "IN6")
		(34 "In16.Cu" signal "GND7")
		(2 "B.Cu" signal "BOTTOM")
		(9 "F.Adhes" user "F.Adhesive")
		(11 "B.Adhes" user "B.Adhesive")
		(13 "F.Paste" user "Package Geometry/Pastemask Top")
		(15 "B.Paste" user "Package Geometry/Pastemask Bottom")
		(5 "F.SilkS" user "Ref Des/Silkscreen Top")
		(7 "B.SilkS" user "Ref Des/Silkscreen Bottom")
		(1 "F.Mask" user "Board Geometry/Soldermask Top")
		(3 "B.Mask" user "Board Geometry/Soldermask Bottom")
		(17 "Dwgs.User" user "User.Drawings")
		(19 "Cmts.User" user "User.Comments")
		(21 "Eco1.User" user "User.Eco1")
		(23 "Eco2.User" user "User.Eco2")
		(25 "Edge.Cuts" user "Board Geometry/Outline")
		(27 "Margin" user)
		(31 "F.CrtYd" user "Package Geometry/Place Bound Top")
		(29 "B.CrtYd" user "Package Geometry/Place Bound Bottom")
		(35 "F.Fab" user "Ref Des/Assembly Top")
		(33 "B.Fab" user "Ref Des/Assembly Bottom")
	)
	(footprint ""
		(layer "F.Cu")
		(at 26.793444 -425.593256 180)
		(property "Reference" "R3284"
			(at 0 0 180)
			(layer "F.SilkS")
			(hide yes)
			(effects
				(font
					(size 1.27 1.27)
				)
			)
		)
		(property "Value" ""
			(at 0 0 180)
			(layer "F.Fab")
			(effects
				(font
					(size 1.27 1.27)
				)
			)
		)
		(duplicate_pad_numbers_are_jumpers no)
		(fp_line
			(start 0.7874 0.4064)
			(end -0.7874 0.4064)
			(stroke
				(width 0.1524)
				(type default)
			)
			(layer "F.SilkS")
		)
		(fp_line
			(start 0.7874 -0.4064)
			(end 0.7874 0.4064)
			(stroke
				(width 0.1524)
				(type default)
			)
			(layer "F.SilkS")
		)
		(fp_line
			(start -0.7874 0.4064)
			(end -0.7874 -0.4064)
			(stroke
				(width 0.1524)
				(type default)
			)
			(layer "F.SilkS")
		)
		(fp_line
			(start -0.7874 -0.4064)
			(end 0.7874 -0.4064)
			(stroke
				(width 0.1524)
				(type default)
			)
			(layer "F.SilkS")
		)
		(fp_line
			(start 0.67945 0.3048)
			(end 0.120396 0.3048)
			(stroke
				(width 0.1)
				(type default)
			)
			(layer "F.Fab")
		)
		(fp_line
			(start 0.67945 -0.3048)
			(end 0.67945 0.3048)
			(stroke
				(width 0.1)
				(type default)
			)
			(layer "F.Fab")
		)
		(fp_line
			(start 0.12065 -0.2794)
			(end 0.12065 -0.3048)
			(stroke
				(width 0.1)
				(type default)
			)
			(layer "F.Fab")
		)
		(fp_line
			(start 0.12065 -0.3048)
			(end 0.67945 -0.3048)
			(stroke
				(width 0.1)
				(type default)
			)
			(layer "F.Fab")
		)
		(fp_line
			(start 0.120396 0.3048)
			(end 0.120396 0.2794)
			(stroke
				(width 0.1)
				(type default)
			)
			(layer "F.Fab")
		)
		(fp_line
			(start 0.120396 0.2794)
			(end -0.12065 0.2794)
			(stroke
				(width 0.1)
				(type default)
			)
			(layer "F.Fab")
		)
		(fp_line
			(start -0.12065 0.3048)
			(end -0.67945 0.3048)
			(stroke
				(width 0.1)
				(type default)
			)
			(layer "F.Fab")
		)
		(fp_line
			(start -0.12065 0.2794)
			(end -0.12065 0.3048)
			(stroke
				(width 0.1)
				(type default)
			)
			(layer "F.Fab")
		)
		(fp_line
			(start -0.12065 -0.2794)
			(end 0.12065 -0.2794)
			(stroke
				(width 0.1)
				(type default)
			)
			(layer "F.Fab")
		)
		(fp_line
			(start -0.12065 -0.305054)
			(end -0.12065 -0.2794)
			(stroke
				(width 0.1)
				(type default)
			)
			(layer "F.Fab")
		)
		(fp_line
			(start -0.67945 0.3048)
			(end -0.67945 -0.305054)
			(stroke
				(width 0.1)
				(type default)
			)
			(layer "F.Fab")
		)
		(fp_line
			(start -0.67945 -0.305054)
			(end -0.12065 -0.305054)
			(stroke
				(width 0.1)
				(type default)
			)
			(layer "F.Fab")
		)
		(pad "1" smd circle
			(at -0.40005 0 180)
			(size 0 0)
			(layers "F.Cu" "F.Mask" "F.Paste")
			(net "FM_P2E_EQB0")
		)
		(pad "2" smd circle
			(at 0.40005 0 180)
			(size 0 0)
			(layers "F.Cu" "F.Mask" "F.Paste")
			(net "GND")
		)
	)
	(footprint ""
		(layer "F.Cu")
		(at 168.656 -433.878736)
		(property "Reference" "R2672"
			(at 0 0 0)
			(layer "F.SilkS")
			(hide yes)
			(effects
				(font
					(size 1.27 1.27)
				)
			)
		)
		(property "Value" ""
			(at 0 0 0)
			(layer "F.Fab")
			(effects
				(font
					(size 1.27 1.27)
				)
			)
		)
		(duplicate_pad_numbers_are_jumpers no)
		(fp_line
			(start -0.7874 -0.4064)
			(end 0.7874 -0.4064)
			(stroke
				(width 0.1524)
				(type default)
			)
			(layer "F.SilkS")
		)
		(fp_line
			(start -0.7874 0.4064)
			(end -0.7874 -0.4064)
			(stroke
				(width 0.1524)
				(type default)
			)
			(layer "F.SilkS")
		)
		(fp_line
			(start 0.7874 -0.4064)
			(end 0.7874 0.4064)
			(stroke
				(width 0.1524)
				(type default)
			)
			(layer "F.SilkS")
		)
		(fp_line
			(start 0.7874 0.4064)
			(end -0.7874 0.4064)
			(stroke
				(width 0.1524)
				(type default)
			)
			(layer "F.SilkS")
		)
		(fp_line
			(start -0.67945 -0.305054)
			(end -0.12065 -0.305054)
			(stroke
				(width 0.1)
				(type default)
			)
			(layer "F.Fab")
		)
		(fp_line
			(start -0.67945 0.3048)
			(end -0.67945 -0.305054)
			(stroke
				(width 0.1)
				(type default)
			)
			(layer "F.Fab")
		)
		(fp_line
			(start -0.12065 -0.305054)
			(end -0.12065 -0.2794)
			(stroke
				(width 0.1)
				(type default)
			)
			(layer "F.Fab")
		)
		(fp_line
			(start -0.12065 -0.2794)
			(end 0.12065 -0.2794)
			(stroke
				(width 0.1)
				(type default)
			)
			(layer "F.Fab")
		)
		(fp_line
			(start -0.12065 0.2794)
			(end -0.12065 0.3048)
			(stroke
				(width 0.1)
				(type default)
			)
			(layer "F.Fab")
		)
		(fp_line
			(start -0.12065 0.3048)
			(end -0.67945 0.3048)
			(stroke
				(width 0.1)
				(type default)
			)
			(layer "F.Fab")
		)
		(fp_line
			(start 0.120396 0.2794)
			(end -0.12065 0.2794)
			(stroke
				(width 0.1)
				(type default)
			)
			(layer "F.Fab")
		)
		(fp_line
			(start 0.120396 0.3048)
			(end 0.120396 0.2794)
			(stroke
				(width 0.1)
				(type default)
			)
			(layer "F.Fab")
		)
		(fp_line
			(start 0.12065 -0.3048)
			(end 0.67945 -0.3048)
			(stroke
				(width 0.1)
				(type default)
			)
			(layer "F.Fab")
		)
		(fp_line
			(start 0.12065 -0.2794)
			(end 0.12065 -0.3048)
			(stroke
				(width 0.1)
				(type default)
			)
			(layer "F.Fab")
		)
		(fp_line
			(start 0.67945 -0.3048)
			(end 0.67945 0.3048)
			(stroke
				(width 0.1)
				(type default)
			)
			(layer "F.Fab")
		)
		(fp_line
			(start 0.67945 0.3048)
			(end 0.120396 0.3048)
			(stroke
				(width 0.1)
				(type default)
			)
			(layer "F.Fab")
		)
		(pad "1" smd circle
			(at -0.40005 0)
			(size 0 0)
			(layers "F.Cu" "F.Mask" "F.Paste")
			(net "SMB_BMC_SWB_BUF_R_SDA")
		)
		(pad "2" smd circle
			(at 0.40005 0)
			(size 0 0)
			(layers "F.Cu" "F.Mask" "F.Paste")
			(net "SMB_BMC_SWB_BUF_SDA")
		)
	)
)
